# S9S_MB_2U (Grand Teton) — schematic netlist excerpt (pin names and nets, part order shuffled) for the footprints in the layout excerpt that follows; sources: Cadence DE-HDL packaged netlist, KiCad conversion of 03242023_DA0F0TMBIJ0_F0T_Motherboard_J_brd_V01_OCP.brd

PU70_P0_2  ISL99390FRZTR5935  ISL99390FRZ-TR5935 IC  pkg QFN21_6X5XB  page 271
  VOS  = PVCCFA_EHV_FIVRA_CPU0_VOS2
  AGND  = GND
  VCC  = PVCCFA_EHV_FIVRA_CPU0_VDD2
  PVCC  = PVCCFA_EHV_FIVRA_CPU0_PVCC2
  PGND1  = GND
  GL1  = NC
  PGND2  = GND
  SW  = SW_PVCCFA_EHV_FIVRA_CPU0_SW2
  VIN1  = SW_P12V_PVCCFA_EHV_FIVRA_CPU0_L
  VIN2  = SW_P12V_PVCCFA_EHV_FIVRA_CPU0_L
  DNC  = NC
  PHASE  = SW_PVCCFA_EHV_FIVRA_CPU0_BOOTR2
  BOOT  = SW_PVCCFA_EHV_FIVRA_CPU0_BOOT2
  PWM  = PVCCFA_EHV_FIVRA_CPU0_PWM2
  EN  = PVCCFA_EHV_FIVRA_CPU0_VDD2
  TOUT_FLT  = PVCCFA_EHV_FIVRA_CPU0_BTSEN
  LSET  = PVCCFA_EHV_FIVRA_CPU0_LSET2
  IOUT  = PVCCFA_EHV_FIVRA_CPU0_IMON2
  REFIN  = PVCCIN_CPU0_VREF
  PGND3  = GND
  GL2  = NC

(kicad_pcb
	(version 20260206)
	(generator "pcbnew")
	(generator_version "10.0")
	(general
		(thickness 1.6)
		(legacy_teardrops no)
	)
	(paper "A4")
	(title_block
		(title "03242023_DA0F0TMBIJ0_F0T_Motherboard_J_brd_V01_OCP.brd")
		(comment 1 "Grand Teton / footprints 2907-2907 of 6105")
	)
	(layers
		(0 "F.Cu" signal "TOP")
		(4 "In1.Cu" signal "GND")
		(6 "In2.Cu" signal "IN1")
		(8 "In3.Cu" signal "GND1")
		(10 "In4.Cu" signal "IN2")
		(12 "In5.Cu" signal "GND2")
		(14 "In6.Cu" signal "IN3")
		(16 "In7.Cu" signal "GND3")
		(18 "In8.Cu" signal "VCC")
		(20 "In9.Cu" signal "VCC1")
		(22 "In10.Cu" signal "GND4")
		(24 "In11.Cu" signal "IN4")
		(26 "In12.Cu" signal "GND5")
		(28 "In13.Cu" signal "IN5")
		(30 "In14.Cu" signal "GND6")
		(32 "In15.Cu" signal "IN6")
		(34 "In16.Cu" signal "GND7")
		(2 "B.Cu" signal "BOTTOM")
		(9 "F.Adhes" user "F.Adhesive")
		(11 "B.Adhes" user "B.Adhesive")
		(13 "F.Paste" user "Package Geometry/Pastemask Top")
		(15 "B.Paste" user "Package Geometry/Pastemask Bottom")
		(5 "F.SilkS" user "Ref Des/Silkscreen Top")
		(7 "B.SilkS" user "Ref Des/Silkscreen Bottom")
		(1 "F.Mask" user "Board Geometry/Soldermask Top")
		(3 "B.Mask" user "Board Geometry/Soldermask Bottom")
		(17 "Dwgs.User" user "User.Drawings")
		(19 "Cmts.User" user "User.Comments")
		(21 "Eco1.User" user "User.Eco1")
		(23 "Eco2.User" user "User.Eco2")
		(25 "Edge.Cuts" user "Board Geometry/Outline")
		(27 "Margin" user)
		(31 "F.CrtYd" user "Package Geometry/Place Bound Top")
		(29 "B.CrtYd" user "Package Geometry/Place Bound Bottom")
		(35 "F.Fab" user "Ref Des/Assembly Top")
		(33 "B.Fab" user "Ref Des/Assembly Bottom")
	)
	(footprint ""
		(layer "F.Cu")
		(at 298.474384 -362.7755)
		(property "Reference" "PU70_P0_2"
			(at 8.245856 -3.740658 0)
			(unlocked yes)
			(layer "F.SilkS")
			(effects
				(font
					(size 0.7874 0.5842)
					(thickness 0.1524)
				)
				(justify left)
			)
		)
		(property "Value" ""
			(at 0 0 0)
			(layer "F.Fab")
			(effects
				(font
					(size 1.27 1.27)
				)
			)
		)
		(duplicate_pad_numbers_are_jumpers no)
		(fp_line
			(start -2.500122 -2.999994)
			(end -2.24409 -2.999994)
			(stroke
				(width 0.1524)
				(type default)
			)
			(layer "F.SilkS")
		)
		(fp_line
			(start -2.500122 -2.529078)
			(end -2.500122 -2.999994)
			(stroke
				(width 0.1524)
				(type default)
			)
			(layer "F.SilkS")
		)
		(fp_line
			(start -2.500122 0.6604)
			(end -2.500122 0.229108)
			(stroke
				(width 0.1524)
				(type default)
			)
			(layer "F.SilkS")
		)
		(fp_line
			(start -2.500122 2.999994)
			(end -2.500122 2.339594)
			(stroke
				(width 0.1524)
				(type default)
			)
			(layer "F.SilkS")
		)
		(fp_line
			(start -2.2987 2.999994)
			(end -2.500122 2.999994)
			(stroke
				(width 0.1524)
				(type default)
			)
			(layer "F.SilkS")
		)
		(fp_line
			(start 2.31394 -2.999994)
			(end 2.500122 -2.999994)
			(stroke
				(width 0.1524)
				(type default)
			)
			(layer "F.SilkS")
		)
		(fp_line
			(start 2.500122 -2.999994)
			(end 2.500122 -2.44348)
			(stroke
				(width 0.1524)
				(type default)
			)
			(layer "F.SilkS")
		)
		(fp_line
			(start 2.500122 2.339594)
			(end 2.500122 2.999994)
			(stroke
				(width 0.1524)
				(type default)
			)
			(layer "F.SilkS")
		)
		(fp_line
			(start 2.500122 2.999994)
			(end 2.2987 2.999994)
			(stroke
				(width 0.1524)
				(type default)
			)
			(layer "F.SilkS")
		)
		(fp_poly
			(pts
				(xy -2.164334 -3.650996) (xy -2.672334 -2.634996) (xy -3.180334 -3.650996)
			)
			(stroke
				(width 0)
				(type default)
			)
			(fill yes)
			(layer "F.SilkS")
		)
		(fp_line
			(start -2.500122 -2.999994)
			(end 2.500122 -2.999994)
			(stroke
				(width 0.1)
				(type default)
			)
			(layer "F.Fab")
		)
		(fp_line
			(start -2.500122 2.999994)
			(end -2.500122 -2.999994)
			(stroke
				(width 0.1)
				(type default)
			)
			(layer "F.Fab")
		)
		(fp_line
			(start 2.500122 -2.999994)
			(end 2.500122 2.999994)
			(stroke
				(width 0.1)
				(type default)
			)
			(layer "F.Fab")
		)
		(fp_line
			(start 2.500122 2.999994)
			(end -2.500122 2.999994)
			(stroke
				(width 0.1)
				(type default)
			)
			(layer "F.Fab")
		)
		(fp_poly
			(pts
				(xy -4.218432 -2.783078) (xy -4.218432 -1.767078) (xy -3.202432 -2.275078)
			)
			(stroke
				(width 0)
				(type default)
			)
			(fill yes)
			(layer "F.Fab")
		)
		(pad "1" smd rect
			(at -2.400046 -2.275078 90)
			(size 0.2286 0.6096)
			(layers "F.Cu" "F.Mask" "F.Paste")
			(net "PVCCFA_EHV_FIVRA_CPU0_VOS2")
		)
		(pad "2" smd rect
			(at -2.400046 -1.82499 90)
			(size 0.2286 0.6096)
			(layers "F.Cu" "F.Mask" "F.Paste")
			(net "GND")
		)
		(pad "3" smd rect
			(at -2.400046 -1.374902 90)
			(size 0.2286 0.6096)
			(layers "F.Cu" "F.Mask" "F.Paste")
			(net "PVCCFA_EHV_FIVRA_CPU0_VDD2")
		)
		(pad "4" smd rect
			(at -2.400046 -0.925068 90)
			(size 0.2286 0.6096)
			(layers "F.Cu" "F.Mask" "F.Paste")
			(net "PVCCFA_EHV_FIVRA_CPU0_PVCC2")
		)
		(pad "5" smd rect
			(at -2.400046 -0.47498 90)
			(size 0.2286 0.6096)
			(layers "F.Cu" "F.Mask" "F.Paste")
			(net "GND")
		)
		(pad "6" smd rect
			(at -2.400046 -0.024892 90)
			(size 0.2286 0.6096)
			(layers "F.Cu" "F.Mask" "F.Paste")
			(net "Net_8514")
		)
		(pad "7_9-20_24" smd circle
			(at 0 1.150112 90)
			(size 0 0)
			(layers "F.Cu" "F.Mask" "F.Paste")
			(net "GND")
		)
		(pad "10_19" smd rect
			(at 0 2.899918 90)
			(size 0.6096 4.318)
			(layers "F.Cu" "F.Mask" "F.Paste")
			(net "SW_PVCCFA_EHV_FIVRA_CPU0_SW2")
		)
		(pad "25_29" smd rect
			(at 1.549908 -1.279906 270)
			(size 2.0574 2.3114)
			(layers "F.Cu" "F.Mask" "F.Paste")
			(net "SW_P12V_PVCCFA_EHV_FIVRA_CPU0_L")
		)
		(pad "30" smd rect
			(at 2.05994 -2.899918)
			(size 0.2286 0.6096)
			(layers "F.Cu" "F.Mask" "F.Paste")
			(net "SW_P12V_PVCCFA_EHV_FIVRA_CPU0_L")
		)
		(pad "31" smd rect
			(at 1.610106 -2.899918)
			(size 0.2286 0.6096)
			(layers "F.Cu" "F.Mask" "F.Paste")
			(net "Net_8515")
		)
		(pad "32" smd rect
			(at 1.160018 -2.899918)
			(size 0.2286 0.6096)
			(layers "F.Cu" "F.Mask" "F.Paste")
			(net "SW_PVCCFA_EHV_FIVRA_CPU0_BOOTR2")
		)
		(pad "33" smd rect
			(at 0.70993 -2.899918)
			(size 0.2286 0.6096)
			(layers "F.Cu" "F.Mask" "F.Paste")
			(net "SW_PVCCFA_EHV_FIVRA_CPU0_BOOT2")
		)
		(pad "34" smd rect
			(at 0.260096 -2.899918)
			(size 0.2286 0.6096)
			(layers "F.Cu" "F.Mask" "F.Paste")
			(net "PVCCFA_EHV_FIVRA_CPU0_PWM2")
		)
		(pad "35" smd rect
			(at -0.189992 -2.899918)
			(size 0.2286 0.6096)
			(layers "F.Cu" "F.Mask" "F.Paste")
			(net "PVCCFA_EHV_FIVRA_CPU0_VDD2")
		)
		(pad "36" smd rect
			(at -0.64008 -2.899918)
			(size 0.2286 0.6096)
			(layers "F.Cu" "F.Mask" "F.Paste")
			(net "PVCCFA_EHV_FIVRA_CPU0_BTSEN")
		)
		(pad "37" smd rect
			(at -1.089914 -2.899918)
			(size 0.2286 0.6096)
			(layers "F.Cu" "F.Mask" "F.Paste")
			(net "PVCCFA_EHV_FIVRA_CPU0_LSET2")
		)
		(pad "38" smd rect
			(at -1.540002 -2.899918)
			(size 0.2286 0.6096)
			(layers "F.Cu" "F.Mask" "F.Paste")
			(net "PVCCFA_EHV_FIVRA_CPU0_IMON2")
		)
		(pad "39" smd rect
			(at -1.99009 -2.899918)
			(size 0.2286 0.6096)
			(layers "F.Cu" "F.Mask" "F.Paste")
			(net "PVCCIN_CPU0_VREF")
		)
		(pad "40" smd rect
			(at -0.87503 -1.27508)
			(size 1.7526 1.9558)
			(layers "F.Cu" "F.Mask" "F.Paste")
			(net "GND")
		)
		(pad "41" smd rect
			(at -1.525016 0.249936 270)
			(size 0.3048 0.4572)
			(layers "F.Cu" "F.Mask" "F.Paste")
			(net "Net_8513")
		)
		(zone
			(layer "F.Cu")
			(hatch none 0.5)
			(connect_pads
				(clearance 0)
			)
			(min_thickness 0.25)
			(keepout
				(tracks not_allowed)
				(vias allowed)
				(pads allowed)
				(copperpour not_allowed)
				(footprints allowed)
			)
			(placement
				(enabled no)
				(sheetname "")
			)
			(fill
				(thermal_gap 0.5)
				(thermal_bridge_width 0.5)
				(island_removal_mode 0)
			)
			(polygon
				(pts
					(xy 295.974262 -359.775506) (xy 295.974262 -360.512868) (xy 300.974506 -360.512868) (xy 300.974506 -359.775506)
					(xy 300.684184 -359.775506) (xy 300.684184 -360.231182) (xy 296.264584 -360.231182) (xy 296.264584 -359.775506)
				)
			)
		)
		(zone
			(layer "F.Cu")
			(hatch none 0.5)
			(connect_pads
				(clearance 0)
			)
			(min_thickness 0.25)
			(keepout
				(tracks not_allowed)
				(vias allowed)
				(pads allowed)
				(copperpour not_allowed)
				(footprints allowed)
			)
			(placement
				(enabled no)
				(sheetname "")
			)
			(fill
				(thermal_gap 0.5)
				(thermal_bridge_width 0.5)
				(island_removal_mode 0)
			)
			(polygon
				(pts
					(xy 296.73296 -363.02188) (xy 297.44924 -363.02188) (xy 297.44924 -362.699808) (xy 297.523662 -362.699808)
					(xy 297.523662 -362.075222) (xy 297.47464 -362.0262) (xy 295.974262 -362.0262) (xy 295.974262 -362.482892)
					(xy 296.669968 -362.482892) (xy 296.669968 -362.322364) (xy 297.228768 -362.322364) (xy 297.228768 -362.728764)
					(xy 296.669968 -362.728764) (xy 296.669968 -362.508292) (xy 295.974262 -362.508292) (xy 295.974262 -362.635292)
					(xy 296.429938 -362.635292) (xy 296.429938 -362.994448) (xy 296.73296 -362.994448)
				)
			)
		)
	)
)
